# T6G (Grand Teton) — schematic netlist excerpt (pin names and nets, part order shuffled) for the footprints in the layout excerpt that follows; sources: Cadence DE-HDL packaged netlist, KiCad conversion of 04192023_DAF0TMB3IC0_F0TG_MB_C_brd_V02_OCP.brd

R29  Q_RES  0 5% CHIP  pkg 0402LF  page 28 : A = SMB_CPU0_3_R_SCL ; B = SMB_CPU0_3_SCL
PC6527  Q_CAP  22UF 4V 20% X6S  pkg C0805  page 361 : A = P1V8_CPU1_RT_1D ; B = GND
PR6604  Q_RES  5.36K 1% EMPTY  pkg 0402LF  page 362 : A = P5V_AUX ; B = P0V9_RETIMER_CPU0_VMON

(kicad_pcb
	(version 20260206)
	(generator "pcbnew")
	(generator_version "10.0")
	(general
		(thickness 1.6)
		(legacy_teardrops no)
	)
	(paper "A4")
	(title_block
		(title "04192023_DAF0TMB3IC0_F0TG_MB_C_brd_V02_OCP.brd")
		(comment 1 "Grand Teton / footprints 7986-7988 of 8354")
	)
	(layers
		(0 "F.Cu" signal "TOP")
		(4 "In1.Cu" signal "GND")
		(6 "In2.Cu" signal "IN1")
		(8 "In3.Cu" signal "GND1")
		(10 "In4.Cu" signal "IN2")
		(12 "In5.Cu" signal "GND2")
		(14 "In6.Cu" signal "IN3")
		(16 "In7.Cu" signal "GND3")
		(18 "In8.Cu" signal "VCC")
		(20 "In9.Cu" signal "VCC1")
		(22 "In10.Cu" signal "GND4")
		(24 "In11.Cu" signal "IN4")
		(26 "In12.Cu" signal "GND5")
		(28 "In13.Cu" signal "IN5")
		(30 "In14.Cu" signal "GND6")
		(32 "In15.Cu" signal "IN6")
		(34 "In16.Cu" signal "GND7")
		(2 "B.Cu" signal "BOTTOM")
		(9 "F.Adhes" user "F.Adhesive")
		(11 "B.Adhes" user "B.Adhesive")
		(13 "F.Paste" user "Package Geometry/Pastemask Top")
		(15 "B.Paste" user "Package Geometry/Pastemask Bottom")
		(5 "F.SilkS" user "Ref Des/Silkscreen Top")
		(7 "B.SilkS" user "Ref Des/Silkscreen Bottom")
		(1 "F.Mask" user "Board Geometry/Soldermask Top")
		(3 "B.Mask" user "Board Geometry/Soldermask Bottom")
		(17 "Dwgs.User" user "User.Drawings")
		(19 "Cmts.User" user "User.Comments")
		(21 "Eco1.User" user "User.Eco1")
		(23 "Eco2.User" user "User.Eco2")
		(25 "Edge.Cuts" user "Board Geometry/Outline")
		(27 "Margin" user)
		(31 "F.CrtYd" user "Package Geometry/Place Bound Top")
		(29 "B.CrtYd" user "Package Geometry/Place Bound Bottom")
		(35 "F.Fab" user "Ref Des/Assembly Top")
		(33 "B.Fab" user "Ref Des/Assembly Bottom")
	)
	(footprint ""
		(layer "B.Cu")
		(at 388.537958 -202.612752 180)
		(property "Reference" "R29"
			(at 0 0 0)
			(layer "B.SilkS")
			(hide yes)
			(effects
				(font
					(size 1.27 1.27)
				)
				(justify mirror)
			)
		)
		(property "Value" ""
			(at 0 0 0)
			(layer "B.Fab")
			(effects
				(font
					(size 1.27 1.27)
				)
				(justify mirror)
			)
		)
		(duplicate_pad_numbers_are_jumpers no)
		(fp_line
			(start 0.7874 0.4064)
			(end 0.7874 -0.4064)
			(stroke
				(width 0.1524)
				(type default)
			)
			(layer "B.SilkS")
		)
		(fp_line
			(start 0.7874 -0.4064)
			(end -0.7874 -0.4064)
			(stroke
				(width 0.1524)
				(type default)
			)
			(layer "B.SilkS")
		)
		(fp_line
			(start -0.7874 0.4064)
			(end 0.7874 0.4064)
			(stroke
				(width 0.1524)
				(type default)
			)
			(layer "B.SilkS")
		)
		(fp_line
			(start -0.7874 -0.4064)
			(end -0.7874 0.4064)
			(stroke
				(width 0.1524)
				(type default)
			)
			(layer "B.SilkS")
		)
		(fp_line
			(start 0.67945 0.3048)
			(end 0.67945 -0.305054)
			(stroke
				(width 0.1)
				(type default)
			)
			(layer "B.Fab")
		)
		(fp_line
			(start 0.67945 -0.305054)
			(end 0.12065 -0.305054)
			(stroke
				(width 0.1)
				(type default)
			)
			(layer "B.Fab")
		)
		(fp_line
			(start 0.12065 0.3048)
			(end 0.67945 0.3048)
			(stroke
				(width 0.1)
				(type default)
			)
			(layer "B.Fab")
		)
		(fp_line
			(start 0.12065 0.2794)
			(end 0.12065 0.3048)
			(stroke
				(width 0.1)
				(type default)
			)
			(layer "B.Fab")
		)
		(fp_line
			(start 0.12065 -0.2794)
			(end -0.12065 -0.2794)
			(stroke
				(width 0.1)
				(type default)
			)
			(layer "B.Fab")
		)
		(fp_line
			(start 0.12065 -0.305054)
			(end 0.12065 -0.2794)
			(stroke
				(width 0.1)
				(type default)
			)
			(layer "B.Fab")
		)
		(fp_line
			(start -0.120396 0.3048)
			(end -0.120396 0.2794)
			(stroke
				(width 0.1)
				(type default)
			)
			(layer "B.Fab")
		)
		(fp_line
			(start -0.120396 0.2794)
			(end 0.12065 0.2794)
			(stroke
				(width 0.1)
				(type default)
			)
			(layer "B.Fab")
		)
		(fp_line
			(start -0.12065 -0.2794)
			(end -0.12065 -0.3048)
			(stroke
				(width 0.1)
				(type default)
			)
			(layer "B.Fab")
		)
		(fp_line
			(start -0.12065 -0.3048)
			(end -0.67945 -0.3048)
			(stroke
				(width 0.1)
				(type default)
			)
			(layer "B.Fab")
		)
		(fp_line
			(start -0.67945 0.3048)
			(end -0.120396 0.3048)
			(stroke
				(width 0.1)
				(type default)
			)
			(layer "B.Fab")
		)
		(fp_line
			(start -0.67945 -0.3048)
			(end -0.67945 0.3048)
			(stroke
				(width 0.1)
				(type default)
			)
			(layer "B.Fab")
		)
		(pad "1" smd circle
			(at 0.40005 0)
			(size 0 0)
			(layers "B.Cu" "B.Mask" "B.Paste")
			(net "SMB_CPU0_3_R_SCL")
		)
		(pad "2" smd circle
			(at -0.40005 0)
			(size 0 0)
			(layers "B.Cu" "B.Mask" "B.Paste")
			(net "SMB_CPU0_3_SCL")
		)
	)
	(footprint ""
		(layer "B.Cu")
		(at 228.834442 -315.95568 -90)
		(property "Reference" "PC6527"
			(at 0 0 90)
			(layer "B.SilkS")
			(hide yes)
			(effects
				(font
					(size 1.27 1.27)
				)
				(justify mirror)
			)
		)
		(property "Value" ""
			(at 0 0 90)
			(layer "B.Fab")
			(effects
				(font
					(size 1.27 1.27)
				)
				(justify mirror)
			)
		)
		(duplicate_pad_numbers_are_jumpers no)
		(fp_line
			(start -1.524 0.762)
			(end 1.524 0.762)
			(stroke
				(width 0.1524)
				(type default)
			)
			(layer "B.SilkS")
		)
		(fp_line
			(start 1.524 0.762)
			(end 1.524 -0.762)
			(stroke
				(width 0.1524)
				(type default)
			)
			(layer "B.SilkS")
		)
		(fp_line
			(start -1.524 -0.762)
			(end -1.524 0.762)
			(stroke
				(width 0.1524)
				(type default)
			)
			(layer "B.SilkS")
		)
		(fp_line
			(start 1.524 -0.762)
			(end -1.524 -0.762)
			(stroke
				(width 0.1524)
				(type default)
			)
			(layer "B.SilkS")
		)
		(fp_line
			(start -1.1049 0.724916)
			(end -1.1049 -0.724916)
			(stroke
				(width 0.1)
				(type default)
			)
			(layer "B.Fab")
		)
		(fp_line
			(start 1.1049 0.724916)
			(end -1.1049 0.724916)
			(stroke
				(width 0.1)
				(type default)
			)
			(layer "B.Fab")
		)
		(fp_line
			(start -1.1049 -0.724916)
			(end 1.1049 -0.724916)
			(stroke
				(width 0.1)
				(type default)
			)
			(layer "B.Fab")
		)
		(fp_line
			(start 1.1049 -0.724916)
			(end 1.1049 0.724916)
			(stroke
				(width 0.1)
				(type default)
			)
			(layer "B.Fab")
		)
		(pad "1" smd rect
			(at 0.889 0 270)
			(size 1.016 1.27)
			(layers "B.Cu" "B.Mask" "B.Paste")
			(net "P1V8_CPU1_RT_1D")
		)
		(pad "2" smd rect
			(at -0.889 0 270)
			(size 1.016 1.27)
			(layers "B.Cu" "B.Mask" "B.Paste")
			(net "GND")
		)
	)
	(footprint ""
		(layer "B.Cu")
		(at 447.656966 -421.374824)
		(property "Reference" "PR6604"
			(at 0 0 0)
			(layer "B.SilkS")
			(hide yes)
			(effects
				(font
					(size 1.27 1.27)
				)
				(justify mirror)
			)
		)
		(property "Value" ""
			(at 0 0 0)
			(layer "B.Fab")
			(effects
				(font
					(size 1.27 1.27)
				)
				(justify mirror)
			)
		)
		(duplicate_pad_numbers_are_jumpers no)
		(fp_line
			(start -0.7874 -0.4064)
			(end -0.7874 0.4064)
			(stroke
				(width 0.1524)
				(type default)
			)
			(layer "B.SilkS")
		)
		(fp_line
			(start -0.7874 0.4064)
			(end 0.7874 0.4064)
			(stroke
				(width 0.1524)
				(type default)
			)
			(layer "B.SilkS")
		)
		(fp_line
			(start 0.7874 -0.4064)
			(end -0.7874 -0.4064)
			(stroke
				(width 0.1524)
				(type default)
			)
			(layer "B.SilkS")
		)
		(fp_line
			(start 0.7874 0.4064)
			(end 0.7874 -0.4064)
			(stroke
				(width 0.1524)
				(type default)
			)
			(layer "B.SilkS")
		)
		(fp_line
			(start -0.67945 -0.3048)
			(end -0.67945 0.3048)
			(stroke
				(width 0.1)
				(type default)
			)
			(layer "B.Fab")
		)
		(fp_line
			(start -0.67945 0.3048)
			(end -0.120396 0.3048)
			(stroke
				(width 0.1)
				(type default)
			)
			(layer "B.Fab")
		)
		(fp_line
			(start -0.12065 -0.3048)
			(end -0.67945 -0.3048)
			(stroke
				(width 0.1)
				(type default)
			)
			(layer "B.Fab")
		)
		(fp_line
			(start -0.12065 -0.2794)
			(end -0.12065 -0.3048)
			(stroke
				(width 0.1)
				(type default)
			)
			(layer "B.Fab")
		)
		(fp_line
			(start -0.120396 0.2794)
			(end 0.12065 0.2794)
			(stroke
				(width 0.1)
				(type default)
			)
			(layer "B.Fab")
		)
		(fp_line
			(start -0.120396 0.3048)
			(end -0.120396 0.2794)
			(stroke
				(width 0.1)
				(type default)
			)
			(layer "B.Fab")
		)
		(fp_line
			(start 0.12065 -0.305054)
			(end 0.12065 -0.2794)
			(stroke
				(width 0.1)
				(type default)
			)
			(layer "B.Fab")
		)
		(fp_line
			(start 0.12065 -0.2794)
			(end -0.12065 -0.2794)
			(stroke
				(width 0.1)
				(type default)
			)
			(layer "B.Fab")
		)
		(fp_line
			(start 0.12065 0.2794)
			(end 0.12065 0.3048)
			(stroke
				(width 0.1)
				(type default)
			)
			(layer "B.Fab")
		)
		(fp_line
			(start 0.12065 0.3048)
			(end 0.67945 0.3048)
			(stroke
				(width 0.1)
				(type default)
			)
			(layer "B.Fab")
		)
		(fp_line
			(start 0.67945 -0.305054)
			(end 0.12065 -0.305054)
			(stroke
				(width 0.1)
				(type default)
			)
			(layer "B.Fab")
		)
		(fp_line
			(start 0.67945 0.3048)
			(end 0.67945 -0.305054)
			(stroke
				(width 0.1)
				(type default)
			)
			(layer "B.Fab")
		)
		(pad "1" smd circle
			(at 0.40005 0 180)
			(size 0 0)
			(layers "B.Cu" "B.Mask" "B.Paste")
			(net "P5V_AUX")
		)
		(pad "2" smd circle
			(at -0.40005 0 180)
			(size 0 0)
			(layers "B.Cu" "B.Mask" "B.Paste")
			(net "P0V9_RETIMER_CPU0_VMON")
		)
	)
)
